# S9S_MB_2U (Grand Teton) — schematic netlist excerpt (pin names and nets, part order shuffled) for the footprints in the layout excerpt that follows; sources: Cadence DE-HDL packaged netlist, KiCad conversion of 03242023_DA0F0TMBIJ0_F0T_Motherboard_J_brd_V01_OCP.brd

X10  TP_TDR_4P_FTS  TP_TDR_4P_DIP EMPTY  pkg TH  page 309
  S1  = TDR_DIFF_85_IN3_DN
  P1  = T1_GND
  P2  = T1_GND
  S2  = TDR_DIFF_85_IN3_DP

H97  HOLE  EMPTY  pkg TH  page 311 : \1\ = GND

(kicad_pcb
	(version 20260206)
	(generator "pcbnew")
	(generator_version "10.0")
	(general
		(thickness 1.6)
		(legacy_teardrops no)
	)
	(paper "A4")
	(title_block
		(title "03242023_DA0F0TMBIJ0_F0T_Motherboard_J_brd_V01_OCP.brd")
		(comment 1 "Grand Teton / footprints 3809-3810 of 6105")
	)
	(layers
		(0 "F.Cu" signal "TOP")
		(4 "In1.Cu" signal "GND")
		(6 "In2.Cu" signal "IN1")
		(8 "In3.Cu" signal "GND1")
		(10 "In4.Cu" signal "IN2")
		(12 "In5.Cu" signal "GND2")
		(14 "In6.Cu" signal "IN3")
		(16 "In7.Cu" signal "GND3")
		(18 "In8.Cu" signal "VCC")
		(20 "In9.Cu" signal "VCC1")
		(22 "In10.Cu" signal "GND4")
		(24 "In11.Cu" signal "IN4")
		(26 "In12.Cu" signal "GND5")
		(28 "In13.Cu" signal "IN5")
		(30 "In14.Cu" signal "GND6")
		(32 "In15.Cu" signal "IN6")
		(34 "In16.Cu" signal "GND7")
		(2 "B.Cu" signal "BOTTOM")
		(9 "F.Adhes" user "F.Adhesive")
		(11 "B.Adhes" user "B.Adhesive")
		(13 "F.Paste" user "Package Geometry/Pastemask Top")
		(15 "B.Paste" user "Package Geometry/Pastemask Bottom")
		(5 "F.SilkS" user "Ref Des/Silkscreen Top")
		(7 "B.SilkS" user "Ref Des/Silkscreen Bottom")
		(1 "F.Mask" user "Board Geometry/Soldermask Top")
		(3 "B.Mask" user "Board Geometry/Soldermask Bottom")
		(17 "Dwgs.User" user "User.Drawings")
		(19 "Cmts.User" user "User.Comments")
		(21 "Eco1.User" user "User.Eco1")
		(23 "Eco2.User" user "User.Eco2")
		(25 "Edge.Cuts" user "Board Geometry/Outline")
		(27 "Margin" user)
		(31 "F.CrtYd" user "Package Geometry/Place Bound Top")
		(29 "B.CrtYd" user "Package Geometry/Place Bound Bottom")
		(35 "F.Fab" user "Ref Des/Assembly Top")
		(33 "B.Fab" user "Ref Des/Assembly Bottom")
	)
	(footprint ""
		(layer "F.Cu")
		(at 493.36833 -303.592992 90)
		(property "Reference" "X10"
			(at -3.481832 3.05562 90)
			(unlocked yes)
			(layer "F.SilkS")
			(effects
				(font
					(size 0.7874 0.5842)
					(thickness 0.1524)
				)
				(justify left)
			)
		)
		(property "Value" ""
			(at 0 0 90)
			(layer "F.Fab")
			(effects
				(font
					(size 1.27 1.27)
				)
			)
		)
		(property "Device Type" "TP_TDR_4P_FTS_TH-TP_TDR_4P_DIPA"
			(at 1.30175 1.27 180)
			(unlocked yes)
			(layer "F.Fab")
			(hide yes)
			(effects
				(font
					(size 0.635 0.4064)
					(thickness 0.1524)
				)
			)
		)
		(property "User Part Number" "N_A"
			(at 1.30175 1.27 180)
			(unlocked yes)
			(layer "Cmts.User")
			(hide yes)
			(effects
				(font
					(size 0.635 0.4064)
					(thickness 0.1524)
				)
			)
		)
		(duplicate_pad_numbers_are_jumpers no)
		(fp_line
			(start 2.54 -1.27)
			(end 0 -1.27)
			(stroke
				(width 0.1524)
				(type default)
			)
			(layer "F.SilkS")
		)
		(fp_line
			(start 0 -1.27)
			(end 0 -0.635)
			(stroke
				(width 0.1524)
				(type default)
			)
			(layer "F.SilkS")
		)
		(fp_line
			(start 2.54 -1.1303)
			(end 2.54 -1.27)
			(stroke
				(width 0.1524)
				(type default)
			)
			(layer "F.SilkS")
		)
		(fp_line
			(start 0 0.635)
			(end 0 1.905)
			(stroke
				(width 0.1524)
				(type default)
			)
			(layer "F.SilkS")
		)
		(fp_line
			(start 2.54 1.4097)
			(end 2.54 1.1303)
			(stroke
				(width 0.1524)
				(type default)
			)
			(layer "F.SilkS")
		)
		(fp_line
			(start 0 3.175)
			(end 0 3.81)
			(stroke
				(width 0.1524)
				(type default)
			)
			(layer "F.SilkS")
		)
		(fp_line
			(start 2.54 3.81)
			(end 2.54 3.6703)
			(stroke
				(width 0.1524)
				(type default)
			)
			(layer "F.SilkS")
		)
		(fp_line
			(start 0 3.81)
			(end 2.54 3.81)
			(stroke
				(width 0.1524)
				(type default)
			)
			(layer "F.SilkS")
		)
		(fp_poly
			(pts
				(xy -0.761746 0) (xy -2.285746 0.762) (xy -2.285746 -0.762)
			)
			(stroke
				(width 0)
				(type default)
			)
			(fill yes)
			(layer "F.SilkS")
		)
		(fp_line
			(start 2.54 -1.27)
			(end 0 -1.27)
			(stroke
				(width 0.1)
				(type default)
			)
			(layer "F.Fab")
		)
		(fp_line
			(start 0 -1.27)
			(end 0 3.81)
			(stroke
				(width 0.1)
				(type default)
			)
			(layer "F.Fab")
		)
		(fp_line
			(start 2.54 3.81)
			(end 2.54 -1.27)
			(stroke
				(width 0.1)
				(type default)
			)
			(layer "F.Fab")
		)
		(fp_line
			(start 0 3.81)
			(end 2.54 3.81)
			(stroke
				(width 0.1)
				(type default)
			)
			(layer "F.Fab")
		)
		(fp_poly
			(pts
				(xy -0.761746 0) (xy -2.285746 -0.762) (xy -2.285746 0.762)
			)
			(stroke
				(width 0)
				(type default)
			)
			(fill yes)
			(layer "F.Fab")
		)
		(pad "1" thru_hole circle
			(at 0 0 90)
			(size 1.0033 1.0033)
			(drill 0.249936)
			(layers "*.Cu" "*.Mask")
			(remove_unused_layers no)
			(net "TDR_DIFF_85_IN3_DN")
			(clearance 0.10795)
			(thermal_gap 0.10795)
			(padstack
				(mode front_inner_back)
				(layer "Inner"
					(shape circle)
					(size 0.8001 0.8001)
					(clearance 0.1524)
				)
				(layer "B.Cu"
					(shape circle)
					(size 1.0033 1.0033)
					(clearance 0.10795)
				)
			)
		)
		(pad "2" thru_hole circle
			(at 2.54 0 90)
			(size 1.9939 1.9939)
			(drill 0.249936)
			(layers "*.Cu" "*.Mask")
			(remove_unused_layers no)
			(net "T1_GND")
			(clearance 0.10795)
			(thermal_gap 0.10795)
			(padstack
				(mode front_inner_back)
				(layer "Inner"
					(shape circle)
					(size 0.8001 0.8001)
					(clearance 0.1524)
				)
				(layer "B.Cu"
					(shape circle)
					(size 1.9939 1.9939)
					(clearance 0.10795)
				)
			)
		)
		(pad "3" thru_hole circle
			(at 2.54 2.54 90)
			(size 1.9939 1.9939)
			(drill 0.249936)
			(layers "*.Cu" "*.Mask")
			(remove_unused_layers no)
			(net "T1_GND")
			(clearance 0.10795)
			(thermal_gap 0.10795)
			(padstack
				(mode front_inner_back)
				(layer "Inner"
					(shape circle)
					(size 0.8001 0.8001)
					(clearance 0.1524)
				)
				(layer "B.Cu"
					(shape circle)
					(size 1.9939 1.9939)
					(clearance 0.10795)
				)
			)
		)
		(pad "4" thru_hole circle
			(at 0 2.54 90)
			(size 1.0033 1.0033)
			(drill 0.249936)
			(layers "*.Cu" "*.Mask")
			(remove_unused_layers no)
			(net "TDR_DIFF_85_IN3_DP")
			(clearance 0.10795)
			(thermal_gap 0.10795)
			(padstack
				(mode front_inner_back)
				(layer "Inner"
					(shape circle)
					(size 0.8001 0.8001)
					(clearance 0.1524)
				)
				(layer "B.Cu"
					(shape circle)
					(size 1.0033 1.0033)
					(clearance 0.10795)
				)
			)
		)
	)
	(footprint ""
		(layer "F.Cu")
		(at 10.339832 -347.699838)
		(property "Reference" "H97"
			(at -5.945632 -4.789932 0)
			(unlocked yes)
			(layer "F.SilkS")
			(effects
				(font
					(size 0.7874 0.5842)
					(thickness 0.1524)
				)
				(justify left)
			)
		)
		(property "Value" ""
			(at 0 0 0)
			(layer "F.Fab")
			(effects
				(font
					(size 1.27 1.27)
				)
			)
		)
		(duplicate_pad_numbers_are_jumpers no)
		(pad "1" thru_hole circle
			(at 0 0)
			(size 10.0076 10.0076)
			(drill 5.6134)
			(layers "*.Cu" "*.Mask")
			(remove_unused_layers no)
			(net "GND")
			(clearance -1.9431)
		)
	)
)
